(kicad_pcb
	(version 20260206)
	(generator "pcbnew")
	(generator_version "10.0")
	(general
		(thickness 1.6)
		(legacy_teardrops no)
	)
	(paper "A4")
	(title_block
		(title "panther-plus-userver — 13130-1b_20150205.brd")
		(comment 1 "Honey Badger (Wiwynn) / footprints 1111-1118 of 1509")
	)
	(layers
		(0 "F.Cu" signal "TOP")
		(4 "In1.Cu" signal "L2")
		(6 "In2.Cu" signal "L3")
		(8 "In3.Cu" signal "L4")
		(10 "In4.Cu" signal "L5")
		(12 "In5.Cu" signal "L6")
		(14 "In6.Cu" signal "L7")
		(16 "In7.Cu" signal "L8")
		(18 "In8.Cu" signal "L9")
		(20 "In9.Cu" signal "L10")
		(22 "In10.Cu" signal "L11")
		(2 "B.Cu" signal "BOTTOM")
		(9 "F.Adhes" user "F.Adhesive")
		(11 "B.Adhes" user "B.Adhesive")
		(13 "F.Paste" user "Package Geometry/Pastemask Top")
		(15 "B.Paste" user "Package Geometry/Pastemask Bottom")
		(5 "F.SilkS" user "Ref Des/Silkscreen Top")
		(7 "B.SilkS" user "Ref Des/Silkscreen Bottom")
		(1 "F.Mask" user "Board Geometry/Soldermask Top")
		(3 "B.Mask" user "Board Geometry/Soldermask Bottom")
		(17 "Dwgs.User" user "User.Drawings")
		(19 "Cmts.User" user "User.Comments")
		(21 "Eco1.User" user "User.Eco1")
		(23 "Eco2.User" user "User.Eco2")
		(25 "Edge.Cuts" user "Board Geometry/Outline")
		(27 "Margin" user)
		(31 "F.CrtYd" user "Package Geometry/Place Bound Top")
		(29 "B.CrtYd" user "Package Geometry/Place Bound Bottom")
		(35 "F.Fab" user "Ref Des/Assembly Top")
		(33 "B.Fab" user "Ref Des/Assembly Bottom")
	)
	(footprint ""
		(layer "B.Cu")
		(at 119.38 -60.579 -90)
		(property "Reference" "C104"
			(at 0 0 90)
			(layer "B.SilkS")
			(hide yes)
			(effects
				(font
					(size 1.27 1.27)
				)
				(justify mirror)
			)
		)
		(property "Value" "SC10U6D3V3MX-GP"
			(at 0 -2.8194 270)
			(unlocked yes)
			(layer "B.Fab")
			(hide yes)
			(effects
				(font
					(size 1.016 1.016)
					(thickness 0.1524)
				)
				(justify mirror)
			)
		)
		(property "Device Type" "C603H38"
			(at 0 -4.3434 270)
			(unlocked yes)
			(layer "B.Fab")
			(hide yes)
			(effects
				(font
					(size 1.016 1.016)
					(thickness 0.1524)
				)
				(justify mirror)
			)
		)
		(duplicate_pad_numbers_are_jumpers no)
		(fp_line
			(start 0.4064 0)
			(end -0.4064 0)
			(stroke
				(width 0.2286)
				(type default)
			)
			(layer "B.SilkS")
		)
		(fp_rect
			(start 0.635 1.1811)
			(end -0.635 -1.1811)
			(stroke
				(width 0)
				(type default)
			)
			(fill no)
			(layer "B.CrtYd")
		)
		(fp_rect
			(start 0.635 1.1811)
			(end -0.635 -1.1811)
			(stroke
				(width 0)
				(type default)
			)
			(fill no)
			(layer "B.Fab")
		)
		(pad "1" smd custom
			(at 0 -0.6604 90)
			(size 0.19685 0.19685)
			(layers "B.Cu" "B.Mask" "B.Paste")
			(net "PV_VTT_DDR_A")
			(options
				(clearance outline)
				(anchor circle)
			)
			(primitives
				(gr_poly
					(pts
						(arc
							(start 0.508 0.2921)
							(mid 0.478242 0.363942)
							(end 0.4064 0.3937)
						)
						(arc
							(start -0.4064 0.3937)
							(mid -0.478242 0.363942)
							(end -0.508 0.2921)
						)
						(arc
							(start -0.508 -0.2921)
							(mid -0.478242 -0.363942)
							(end -0.4064 -0.3937)
						)
						(arc
							(start 0.4064 -0.3937)
							(mid 0.478242 -0.363942)
							(end 0.508 -0.2921)
						)
					)
					(width 0)
					(fill yes)
				)
			)
		)
		(pad "2" smd custom
			(at 0 0.6604 90)
			(size 0.19685 0.19685)
			(layers "B.Cu" "B.Mask" "B.Paste")
			(net "GND")
			(options
				(clearance outline)
				(anchor circle)
			)
			(primitives
				(gr_poly
					(pts
						(arc
							(start 0.508 0.2921)
							(mid 0.478242 0.363942)
							(end 0.4064 0.3937)
						)
						(arc
							(start -0.4064 0.3937)
							(mid -0.478242 0.363942)
							(end -0.508 0.2921)
						)
						(arc
							(start -0.508 -0.2921)
							(mid -0.478242 -0.363942)
							(end -0.4064 -0.3937)
						)
						(arc
							(start 0.4064 -0.3937)
							(mid 0.478242 -0.363942)
							(end 0.508 -0.2921)
						)
					)
					(width 0)
					(fill yes)
				)
			)
		)
	)
	(footprint ""
		(layer "B.Cu")
		(at 8.509 -24.384 -90)
		(property "Reference" "PR118"
			(at 0 0 90)
			(layer "B.SilkS")
			(hide yes)
			(effects
				(font
					(size 1.27 1.27)
				)
				(justify mirror)
			)
		)
		(property "Value" "475KR2F-GP"
			(at -1.7907 -1.1176 270)
			(unlocked yes)
			(layer "B.Fab")
			(hide yes)
			(effects
				(font
					(size 1.016 1.016)
					(thickness 0.1524)
				)
				(justify mirror)
			)
		)
		(property "Device Type" "R402H16"
			(at -1.7907 -2.6416 270)
			(unlocked yes)
			(layer "B.Fab")
			(hide yes)
			(effects
				(font
					(size 1.016 1.016)
					(thickness 0.1524)
				)
				(justify mirror)
			)
		)
		(duplicate_pad_numbers_are_jumpers no)
		(fp_rect
			(start 0.381 0.8382)
			(end -0.381 -0.8382)
			(stroke
				(width 0)
				(type default)
			)
			(fill no)
			(layer "B.CrtYd")
		)
		(fp_rect
			(start 0.381 0.8382)
			(end -0.381 -0.8382)
			(stroke
				(width 0)
				(type default)
			)
			(fill no)
			(layer "B.Fab")
		)
		(pad "1" smd custom
			(at 0 -0.4318 90)
			(size 0.127 0.127)
			(layers "B.Cu" "B.Mask" "B.Paste")
			(net "P1V0_VREG")
			(options
				(clearance outline)
				(anchor circle)
			)
			(primitives
				(gr_poly
					(pts
						(arc
							(start -0.2032 0.2794)
							(mid -0.239121 0.264521)
							(end -0.254 0.2286)
						)
						(arc
							(start -0.254 -0.2286)
							(mid -0.239121 -0.264521)
							(end -0.2032 -0.2794)
						)
						(arc
							(start 0.2032 -0.2794)
							(mid 0.239121 -0.264521)
							(end 0.254 -0.2286)
						)
						(arc
							(start 0.254 0.2286)
							(mid 0.239121 0.264521)
							(end 0.2032 0.2794)
						)
					)
					(width 0)
					(fill yes)
				)
			)
		)
		(pad "2" smd custom
			(at 0 0.4318 90)
			(size 0.127 0.127)
			(layers "B.Cu" "B.Mask" "B.Paste")
			(net "P1V0_MODE")
			(options
				(clearance outline)
				(anchor circle)
			)
			(primitives
				(gr_poly
					(pts
						(arc
							(start -0.2032 0.2794)
							(mid -0.239121 0.264521)
							(end -0.254 0.2286)
						)
						(arc
							(start -0.254 -0.2286)
							(mid -0.239121 -0.264521)
							(end -0.2032 -0.2794)
						)
						(arc
							(start 0.2032 -0.2794)
							(mid 0.239121 -0.264521)
							(end 0.254 -0.2286)
						)
						(arc
							(start 0.254 0.2286)
							(mid 0.239121 0.264521)
							(end 0.2032 0.2794)
						)
					)
					(width 0)
					(fill yes)
				)
			)
		)
	)
	(footprint ""
		(layer "B.Cu")
		(at 99.187 -20.574 90)
		(property "Reference" "R381"
			(at 0 0 90)
			(layer "B.SilkS")
			(hide yes)
			(effects
				(font
					(size 1.27 1.27)
				)
				(justify mirror)
			)
		)
		(property "Value" "30D1R2F-L-GP"
			(at -0.064008 -3.993896 90)
			(unlocked yes)
			(layer "B.Fab")
			(hide yes)
			(effects
				(font
					(size 1.016 1.016)
					(thickness 0.1524)
				)
				(justify mirror)
			)
		)
		(property "Device Type" "R402H16"
			(at -0.064008 -5.517896 90)
			(unlocked yes)
			(layer "B.Fab")
			(hide yes)
			(effects
				(font
					(size 1.016 1.016)
					(thickness 0.1524)
				)
				(justify mirror)
			)
		)
		(duplicate_pad_numbers_are_jumpers no)
		(fp_rect
			(start 0.381 0.8382)
			(end -0.381 -0.8382)
			(stroke
				(width 0)
				(type default)
			)
			(fill no)
			(layer "B.CrtYd")
		)
		(fp_rect
			(start 0.381 0.8382)
			(end -0.381 -0.8382)
			(stroke
				(width 0)
				(type default)
			)
			(fill no)
			(layer "B.Fab")
		)
		(pad "1" smd custom
			(at 0 -0.4318 270)
			(size 0.127 0.127)
			(layers "B.Cu" "B.Mask" "B.Paste")
			(net "M_B_DQPU")
			(options
				(clearance outline)
				(anchor circle)
			)
			(primitives
				(gr_poly
					(pts
						(arc
							(start -0.2032 0.2794)
							(mid -0.239121 0.264521)
							(end -0.254 0.2286)
						)
						(arc
							(start -0.254 -0.2286)
							(mid -0.239121 -0.264521)
							(end -0.2032 -0.2794)
						)
						(arc
							(start 0.2032 -0.2794)
							(mid 0.239121 -0.264521)
							(end 0.254 -0.2286)
						)
						(arc
							(start 0.254 0.2286)
							(mid 0.239121 0.264521)
							(end 0.2032 0.2794)
						)
					)
					(width 0)
					(fill yes)
				)
			)
		)
		(pad "2" smd custom
			(at 0 0.4318 270)
			(size 0.127 0.127)
			(layers "B.Cu" "B.Mask" "B.Paste")
			(net "GND")
			(options
				(clearance outline)
				(anchor circle)
			)
			(primitives
				(gr_poly
					(pts
						(arc
							(start -0.2032 0.2794)
							(mid -0.239121 0.264521)
							(end -0.254 0.2286)
						)
						(arc
							(start -0.254 -0.2286)
							(mid -0.239121 -0.264521)
							(end -0.2032 -0.2794)
						)
						(arc
							(start 0.2032 -0.2794)
							(mid 0.239121 -0.264521)
							(end 0.254 -0.2286)
						)
						(arc
							(start 0.254 0.2286)
							(mid 0.239121 0.264521)
							(end 0.2032 0.2794)
						)
					)
					(width 0)
					(fill yes)
				)
			)
		)
	)
	(footprint ""
		(layer "B.Cu")
		(at 112.395 -32.274002 90)
		(property "Reference" "R353"
			(at 0 0 90)
			(layer "B.SilkS")
			(hide yes)
			(effects
				(font
					(size 1.27 1.27)
				)
				(justify mirror)
			)
		)
		(property "Value" "0R2J-2-GP"
			(at -0.064008 -3.993896 90)
			(unlocked yes)
			(layer "B.Fab")
			(hide yes)
			(effects
				(font
					(size 1.016 1.016)
					(thickness 0.1524)
				)
				(justify mirror)
			)
		)
		(property "Device Type" "R402H16"
			(at -0.064008 -5.517896 90)
			(unlocked yes)
			(layer "B.Fab")
			(hide yes)
			(effects
				(font
					(size 1.016 1.016)
					(thickness 0.1524)
				)
				(justify mirror)
			)
		)
		(duplicate_pad_numbers_are_jumpers no)
		(fp_rect
			(start 0.381 0.8382)
			(end -0.381 -0.8382)
			(stroke
				(width 0)
				(type default)
			)
			(fill no)
			(layer "B.CrtYd")
		)
		(fp_rect
			(start 0.381 0.8382)
			(end -0.381 -0.8382)
			(stroke
				(width 0)
				(type default)
			)
			(fill no)
			(layer "B.Fab")
		)
		(pad "1" smd custom
			(at 0 -0.4318 270)
			(size 0.127 0.127)
			(layers "B.Cu" "B.Mask" "B.Paste")
			(net "M_DRAM_PWROK")
			(options
				(clearance outline)
				(anchor circle)
			)
			(primitives
				(gr_poly
					(pts
						(arc
							(start -0.2032 0.2794)
							(mid -0.239121 0.264521)
							(end -0.254 0.2286)
						)
						(arc
							(start -0.254 -0.2286)
							(mid -0.239121 -0.264521)
							(end -0.2032 -0.2794)
						)
						(arc
							(start 0.2032 -0.2794)
							(mid 0.239121 -0.264521)
							(end 0.254 -0.2286)
						)
						(arc
							(start 0.254 0.2286)
							(mid 0.239121 0.264521)
							(end 0.2032 0.2794)
						)
					)
					(width 0)
					(fill yes)
				)
			)
		)
		(pad "2" smd custom
			(at 0 0.4318 270)
			(size 0.127 0.127)
			(layers "B.Cu" "B.Mask" "B.Paste")
			(net "GND")
			(options
				(clearance outline)
				(anchor circle)
			)
			(primitives
				(gr_poly
					(pts
						(arc
							(start -0.2032 0.2794)
							(mid -0.239121 0.264521)
							(end -0.254 0.2286)
						)
						(arc
							(start -0.254 -0.2286)
							(mid -0.239121 -0.264521)
							(end -0.2032 -0.2794)
						)
						(arc
							(start 0.2032 -0.2794)
							(mid 0.239121 -0.264521)
							(end 0.254 -0.2286)
						)
						(arc
							(start 0.254 0.2286)
							(mid 0.239121 0.264521)
							(end 0.2032 0.2794)
						)
					)
					(width 0)
					(fill yes)
				)
			)
		)
	)
	(footprint ""
		(layer "B.Cu")
		(at 201.295 -40.005 90)
		(property "Reference" "LED10"
			(at 0 0 90)
			(layer "B.SilkS")
			(hide yes)
			(effects
				(font
					(size 1.27 1.27)
				)
				(justify mirror)
			)
		)
		(property "Value" "LED-YG-51-GP"
			(at 0.0381 -2.6162 90)
			(unlocked yes)
			(layer "B.Fab")
			(hide yes)
			(effects
				(font
					(size 1.016 1.016)
					(thickness 0.1524)
				)
				(justify mirror)
			)
		)
		(property "Device Type" "LED1608AKH40"
			(at 0.0381 -4.1402 90)
			(unlocked yes)
			(layer "B.Fab")
			(hide yes)
			(effects
				(font
					(size 1.016 1.016)
					(thickness 0.1524)
				)
				(justify mirror)
			)
		)
		(duplicate_pad_numbers_are_jumpers no)
		(fp_line
			(start 0.5334 1.3081)
			(end -0.5334 1.3081)
			(stroke
				(width 0.254)
				(type default)
			)
			(layer "B.SilkS")
		)
		(fp_rect
			(start 0.6604 1.1811)
			(end -0.6604 -1.1811)
			(stroke
				(width 0)
				(type default)
			)
			(fill no)
			(layer "B.CrtYd")
		)
		(fp_rect
			(start 0.6604 1.1811)
			(end -0.6604 -1.1811)
			(stroke
				(width 0)
				(type default)
			)
			(fill no)
			(layer "B.Fab")
		)
		(pad "A" smd rect
			(at 0 -0.652526 270)
			(size 1.0668 0.8128)
			(layers "B.Cu" "B.Mask" "B.Paste")
			(net "PORT80_R_BIT5")
		)
		(pad "K" smd rect
			(at 0 0.652526 270)
			(size 1.0668 0.8128)
			(layers "B.Cu" "B.Mask" "B.Paste")
			(net "PORT80_BIT5")
		)
	)
	(footprint ""
		(layer "B.Cu")
		(at 187.0202 -34.8234 90)
		(property "Reference" "PC97"
			(at 0 0 90)
			(layer "B.SilkS")
			(hide yes)
			(effects
				(font
					(size 1.27 1.27)
				)
				(justify mirror)
			)
		)
		(property "Value" "SC1KP50V2KX-1GP"
			(at -1.8923 -1.2065 90)
			(unlocked yes)
			(layer "B.Fab")
			(hide yes)
			(effects
				(font
					(size 1.016 1.016)
					(thickness 0.1524)
				)
				(justify mirror)
			)
		)
		(property "Device Type" "C402H22"
			(at -1.8923 -2.7305 90)
			(unlocked yes)
			(layer "B.Fab")
			(hide yes)
			(effects
				(font
					(size 1.016 1.016)
					(thickness 0.1524)
				)
				(justify mirror)
			)
		)
		(duplicate_pad_numbers_are_jumpers no)
		(fp_rect
			(start 0.381 0.7366)
			(end -0.381 -0.7366)
			(stroke
				(width 0)
				(type default)
			)
			(fill no)
			(layer "B.CrtYd")
		)
		(fp_rect
			(start 0.381 0.7366)
			(end -0.381 -0.7366)
			(stroke
				(width 0)
				(type default)
			)
			(fill no)
			(layer "B.Fab")
		)
		(pad "1" smd custom
			(at 0 -0.4572 270)
			(size 0.1143 0.1143)
			(layers "B.Cu" "B.Mask" "B.Paste")
			(net "VR_PVDDR_A_IMON")
			(options
				(clearance outline)
				(anchor circle)
			)
			(primitives
				(gr_poly
					(pts
						(arc
							(start -0.254 0.1778)
							(mid -0.239121 0.213721)
							(end -0.2032 0.2286)
						)
						(arc
							(start 0.2032 0.2286)
							(mid 0.239121 0.213721)
							(end 0.254 0.1778)
						)
						(arc
							(start 0.254 -0.1778)
							(mid 0.239121 -0.213721)
							(end 0.2032 -0.2286)
						)
						(arc
							(start -0.2032 -0.2286)
							(mid -0.239121 -0.213721)
							(end -0.254 -0.1778)
						)
					)
					(width 0)
					(fill yes)
				)
			)
		)
		(pad "2" smd custom
			(at 0 0.4572 270)
			(size 0.1143 0.1143)
			(layers "B.Cu" "B.Mask" "B.Paste")
			(net "GND")
			(options
				(clearance outline)
				(anchor circle)
			)
			(primitives
				(gr_poly
					(pts
						(arc
							(start -0.254 0.1778)
							(mid -0.239121 0.213721)
							(end -0.2032 0.2286)
						)
						(arc
							(start 0.2032 0.2286)
							(mid 0.239121 0.213721)
							(end 0.254 0.1778)
						)
						(arc
							(start 0.254 -0.1778)
							(mid 0.239121 -0.213721)
							(end 0.2032 -0.2286)
						)
						(arc
							(start -0.2032 -0.2286)
							(mid -0.239121 -0.213721)
							(end -0.254 -0.1778)
						)
					)
					(width 0)
					(fill yes)
				)
			)
		)
	)
	(footprint ""
		(layer "B.Cu")
		(at 130.175 -56.388 180)
		(property "Reference" "PC146"
			(at 0 0 0)
			(layer "B.SilkS")
			(hide yes)
			(effects
				(font
					(size 1.27 1.27)
				)
				(justify mirror)
			)
		)
		(property "Value" "SC10U6D3V3MX-GP"
			(at 0 -2.8194 180)
			(unlocked yes)
			(layer "B.Fab")
			(hide yes)
			(effects
				(font
					(size 1.016 1.016)
					(thickness 0.1524)
				)
				(justify mirror)
			)
		)
		(property "Device Type" "C603H38"
			(at 0 -4.3434 180)
			(unlocked yes)
			(layer "B.Fab")
			(hide yes)
			(effects
				(font
					(size 1.016 1.016)
					(thickness 0.1524)
				)
				(justify mirror)
			)
		)
		(duplicate_pad_numbers_are_jumpers no)
		(fp_line
			(start 0.4064 0)
			(end -0.4064 0)
			(stroke
				(width 0.2286)
				(type default)
			)
			(layer "B.SilkS")
		)
		(fp_rect
			(start 0.635 1.1811)
			(end -0.635 -1.1811)
			(stroke
				(width 0)
				(type default)
			)
			(fill no)
			(layer "B.CrtYd")
		)
		(fp_rect
			(start 0.635 1.1811)
			(end -0.635 -1.1811)
			(stroke
				(width 0)
				(type default)
			)
			(fill no)
			(layer "B.Fab")
		)
		(pad "1" smd custom
			(at 0 -0.6604)
			(size 0.19685 0.19685)
			(layers "B.Cu" "B.Mask" "B.Paste")
			(net "GND")
			(options
				(clearance outline)
				(anchor circle)
			)
			(primitives
				(gr_poly
					(pts
						(arc
							(start 0.508 0.2921)
							(mid 0.478242 0.363942)
							(end 0.4064 0.3937)
						)
						(arc
							(start -0.4064 0.3937)
							(mid -0.478242 0.363942)
							(end -0.508 0.2921)
						)
						(arc
							(start -0.508 -0.2921)
							(mid -0.478242 -0.363942)
							(end -0.4064 -0.3937)
						)
						(arc
							(start 0.4064 -0.3937)
							(mid 0.478242 -0.363942)
							(end 0.508 -0.2921)
						)
					)
					(width 0)
					(fill yes)
				)
			)
		)
		(pad "2" smd custom
			(at 0 0.6604)
			(size 0.19685 0.19685)
			(layers "B.Cu" "B.Mask" "B.Paste")
			(net "PV_VTT_DDR_A")
			(options
				(clearance outline)
				(anchor circle)
			)
			(primitives
				(gr_poly
					(pts
						(arc
							(start 0.508 0.2921)
							(mid 0.478242 0.363942)
							(end 0.4064 0.3937)
						)
						(arc
							(start -0.4064 0.3937)
							(mid -0.478242 0.363942)
							(end -0.508 0.2921)
						)
						(arc
							(start -0.508 -0.2921)
							(mid -0.478242 -0.363942)
							(end -0.4064 -0.3937)
						)
						(arc
							(start 0.4064 -0.3937)
							(mid 0.478242 -0.363942)
							(end 0.508 -0.2921)
						)
					)
					(width 0)
					(fill yes)
				)
			)
		)
	)
	(footprint ""
		(layer "B.Cu")
		(at 190.373 -31.623 180)
		(property "Reference" "PR208"
			(at 0 0 0)
			(layer "B.SilkS")
			(hide yes)
			(effects
				(font
					(size 1.27 1.27)
				)
				(justify mirror)
			)
		)
		(property "Value" "5M1R2J-GP"
			(at -1.7907 -1.1176 180)
			(unlocked yes)
			(layer "B.Fab")
			(hide yes)
			(effects
				(font
					(size 1.016 1.016)
					(thickness 0.1524)
				)
				(justify mirror)
			)
		)
		(property "Device Type" "R402H16"
			(at -1.7907 -2.6416 180)
			(unlocked yes)
			(layer "B.Fab")
			(hide yes)
			(effects
				(font
					(size 1.016 1.016)
					(thickness 0.1524)
				)
				(justify mirror)
			)
		)
		(duplicate_pad_numbers_are_jumpers no)
		(fp_rect
			(start 0.381 0.8382)
			(end -0.381 -0.8382)
			(stroke
				(width 0)
				(type default)
			)
			(fill no)
			(layer "B.CrtYd")
		)
		(fp_rect
			(start 0.381 0.8382)
			(end -0.381 -0.8382)
			(stroke
				(width 0)
				(type default)
			)
			(fill no)
			(layer "B.Fab")
		)
		(pad "1" smd custom
			(at 0 -0.4318)
			(size 0.127 0.127)
			(layers "B.Cu" "B.Mask" "B.Paste")
			(net "VR_PVDDRA_ISUMP1")
			(options
				(clearance outline)
				(anchor circle)
			)
			(primitives
				(gr_poly
					(pts
						(arc
							(start -0.2032 0.2794)
							(mid -0.239121 0.264521)
							(end -0.254 0.2286)
						)
						(arc
							(start -0.254 -0.2286)
							(mid -0.239121 -0.264521)
							(end -0.2032 -0.2794)
						)
						(arc
							(start 0.2032 -0.2794)
							(mid 0.239121 -0.264521)
							(end 0.254 -0.2286)
						)
						(arc
							(start 0.254 0.2286)
							(mid 0.239121 0.264521)
							(end 0.2032 0.2794)
						)
					)
					(width 0)
					(fill yes)
				)
			)
		)
		(pad "2" smd custom
			(at 0 0.4318)
			(size 0.127 0.127)
			(layers "B.Cu" "B.Mask" "B.Paste")
			(net "GND")
			(options
				(clearance outline)
				(anchor circle)
			)
			(primitives
				(gr_poly
					(pts
						(arc
							(start -0.2032 0.2794)
							(mid -0.239121 0.264521)
							(end -0.254 0.2286)
						)
						(arc
							(start -0.254 -0.2286)
							(mid -0.239121 -0.264521)
							(end -0.2032 -0.2794)
						)
						(arc
							(start 0.2032 -0.2794)
							(mid 0.239121 -0.264521)
							(end 0.254 -0.2286)
						)
						(arc
							(start 0.254 0.2286)
							(mid 0.239121 0.264521)
							(end 0.2032 0.2794)
						)
					)
					(width 0)
					(fill yes)
				)
			)
		)
	)
)
